(kicad_pcb
	(version 20260206)
	(generator "pcbnew")
	(generator_version "10.0")
	(general
		(thickness 1.6)
		(legacy_teardrops no)
	)
	(paper "A4")
	(title_block
		(title "03242023_DA0F0TMBIJ0_F0T_Motherboard_J_brd_V01_OCP.brd")
		(comment 1 "Grand Teton / footprints 4217-4222 of 6105")
	)
	(layers
		(0 "F.Cu" signal "TOP")
		(4 "In1.Cu" signal "GND")
		(6 "In2.Cu" signal "IN1")
		(8 "In3.Cu" signal "GND1")
		(10 "In4.Cu" signal "IN2")
		(12 "In5.Cu" signal "GND2")
		(14 "In6.Cu" signal "IN3")
		(16 "In7.Cu" signal "GND3")
		(18 "In8.Cu" signal "VCC")
		(20 "In9.Cu" signal "VCC1")
		(22 "In10.Cu" signal "GND4")
		(24 "In11.Cu" signal "IN4")
		(26 "In12.Cu" signal "GND5")
		(28 "In13.Cu" signal "IN5")
		(30 "In14.Cu" signal "GND6")
		(32 "In15.Cu" signal "IN6")
		(34 "In16.Cu" signal "GND7")
		(2 "B.Cu" signal "BOTTOM")
		(9 "F.Adhes" user "F.Adhesive")
		(11 "B.Adhes" user "B.Adhesive")
		(13 "F.Paste" user "Package Geometry/Pastemask Top")
		(15 "B.Paste" user "Package Geometry/Pastemask Bottom")
		(5 "F.SilkS" user "Ref Des/Silkscreen Top")
		(7 "B.SilkS" user "Ref Des/Silkscreen Bottom")
		(1 "F.Mask" user "Board Geometry/Soldermask Top")
		(3 "B.Mask" user "Board Geometry/Soldermask Bottom")
		(17 "Dwgs.User" user "User.Drawings")
		(19 "Cmts.User" user "User.Comments")
		(21 "Eco1.User" user "User.Eco1")
		(23 "Eco2.User" user "User.Eco2")
		(25 "Edge.Cuts" user "Board Geometry/Outline")
		(27 "Margin" user)
		(31 "F.CrtYd" user "Package Geometry/Place Bound Top")
		(29 "B.CrtYd" user "Package Geometry/Place Bound Bottom")
		(35 "F.Fab" user "Ref Des/Assembly Top")
		(33 "B.Fab" user "Ref Des/Assembly Bottom")
	)
	(footprint ""
		(layer "B.Cu")
		(at 329.119992 -65.24752 45)
		(property "Reference" "C1251"
			(at 0 0 45)
			(layer "B.SilkS")
			(hide yes)
			(effects
				(font
					(size 1.27 1.27)
				)
				(justify mirror)
			)
		)
		(property "Value" ""
			(at 0 0 45)
			(layer "B.Fab")
			(effects
				(font
					(size 1.27 1.27)
				)
				(justify mirror)
			)
		)
		(duplicate_pad_numbers_are_jumpers no)
		(fp_line
			(start -1.295492 -0.584255)
			(end -1.295492 0.584255)
			(stroke
				(width 0.1524)
				(type default)
			)
			(layer "B.SilkS")
		)
		(fp_line
			(start -1.295492 0.584255)
			(end 1.295492 0.584255)
			(stroke
				(width 0.1524)
				(type default)
			)
			(layer "B.SilkS")
		)
		(fp_line
			(start 0 -0.584076)
			(end 0 0.584076)
			(stroke
				(width 0.1524)
				(type default)
			)
			(layer "B.SilkS")
		)
		(fp_line
			(start 1.295492 -0.584255)
			(end -1.295492 -0.584255)
			(stroke
				(width 0.1524)
				(type default)
			)
			(layer "B.SilkS")
		)
		(fp_line
			(start 1.295492 0.584255)
			(end 1.295492 -0.584255)
			(stroke
				(width 0.1524)
				(type default)
			)
			(layer "B.SilkS")
		)
		(fp_line
			(start -1.193835 -0.406446)
			(end -1.193835 0.406446)
			(stroke
				(width 0.1)
				(type default)
			)
			(layer "B.Fab")
		)
		(fp_line
			(start -0.863541 -0.457275)
			(end -0.863721 -0.406446)
			(stroke
				(width 0.1)
				(type default)
			)
			(layer "B.Fab")
		)
		(fp_line
			(start -0.863721 -0.406446)
			(end -1.193835 -0.406446)
			(stroke
				(width 0.1)
				(type default)
			)
			(layer "B.Fab")
		)
		(fp_line
			(start -1.193835 0.406446)
			(end -0.863721 0.406446)
			(stroke
				(width 0.1)
				(type default)
			)
			(layer "B.Fab")
		)
		(fp_line
			(start -0.863721 0.406446)
			(end -0.863541 0.457275)
			(stroke
				(width 0.1)
				(type default)
			)
			(layer "B.Fab")
		)
		(fp_line
			(start -0.863541 0.457275)
			(end 0.863541 0.457275)
			(stroke
				(width 0.1)
				(type default)
			)
			(layer "B.Fab")
		)
		(fp_line
			(start 0.863541 -0.457275)
			(end -0.863541 -0.457275)
			(stroke
				(width 0.1)
				(type default)
			)
			(layer "B.Fab")
		)
		(fp_line
			(start 0.863721 -0.406446)
			(end 0.863541 -0.457275)
			(stroke
				(width 0.1)
				(type default)
			)
			(layer "B.Fab")
		)
		(fp_line
			(start 1.193835 -0.406446)
			(end 0.863721 -0.406446)
			(stroke
				(width 0.1)
				(type default)
			)
			(layer "B.Fab")
		)
		(fp_line
			(start 0.863721 0.406446)
			(end 1.193835 0.406446)
			(stroke
				(width 0.1)
				(type default)
			)
			(layer "B.Fab")
		)
		(fp_line
			(start 0.863541 0.457275)
			(end 0.863721 0.406446)
			(stroke
				(width 0.1)
				(type default)
			)
			(layer "B.Fab")
		)
		(fp_line
			(start 1.193835 0.406446)
			(end 1.193835 -0.406446)
			(stroke
				(width 0.1)
				(type default)
			)
			(layer "B.Fab")
		)
		(pad "1" smd rect
			(at 0.7366 0 315)
			(size 0.7112 0.8128)
			(layers "B.Cu" "B.Mask" "B.Paste")
			(net "P1V05_PCH_PLL_AUX")
		)
		(pad "2" smd rect
			(at -0.7366 0 315)
			(size 0.7112 0.8128)
			(layers "B.Cu" "B.Mask" "B.Paste")
			(net "GND")
		)
	)
	(footprint ""
		(layer "B.Cu")
		(at 175.830738 -97.32137 -90)
		(property "Reference" "R162"
			(at 0 0 90)
			(layer "B.SilkS")
			(hide yes)
			(effects
				(font
					(size 1.27 1.27)
				)
				(justify mirror)
			)
		)
		(property "Value" ""
			(at 0 0 90)
			(layer "B.Fab")
			(effects
				(font
					(size 1.27 1.27)
				)
				(justify mirror)
			)
		)
		(duplicate_pad_numbers_are_jumpers no)
		(fp_line
			(start -0.7874 0.4064)
			(end 0.7874 0.4064)
			(stroke
				(width 0.1524)
				(type default)
			)
			(layer "B.SilkS")
		)
		(fp_line
			(start 0.7874 0.4064)
			(end 0.7874 -0.4064)
			(stroke
				(width 0.1524)
				(type default)
			)
			(layer "B.SilkS")
		)
		(fp_line
			(start -0.7874 -0.4064)
			(end -0.7874 0.4064)
			(stroke
				(width 0.1524)
				(type default)
			)
			(layer "B.SilkS")
		)
		(fp_line
			(start 0.7874 -0.4064)
			(end -0.7874 -0.4064)
			(stroke
				(width 0.1524)
				(type default)
			)
			(layer "B.SilkS")
		)
		(fp_line
			(start -0.67945 0.3048)
			(end -0.120396 0.3048)
			(stroke
				(width 0.1)
				(type default)
			)
			(layer "B.Fab")
		)
		(fp_line
			(start -0.120396 0.3048)
			(end -0.120396 0.2794)
			(stroke
				(width 0.1)
				(type default)
			)
			(layer "B.Fab")
		)
		(fp_line
			(start 0.12065 0.3048)
			(end 0.67945 0.3048)
			(stroke
				(width 0.1)
				(type default)
			)
			(layer "B.Fab")
		)
		(fp_line
			(start 0.67945 0.3048)
			(end 0.67945 -0.305054)
			(stroke
				(width 0.1)
				(type default)
			)
			(layer "B.Fab")
		)
		(fp_line
			(start -0.120396 0.2794)
			(end 0.12065 0.2794)
			(stroke
				(width 0.1)
				(type default)
			)
			(layer "B.Fab")
		)
		(fp_line
			(start 0.12065 0.2794)
			(end 0.12065 0.3048)
			(stroke
				(width 0.1)
				(type default)
			)
			(layer "B.Fab")
		)
		(fp_line
			(start -0.12065 -0.2794)
			(end -0.12065 -0.3048)
			(stroke
				(width 0.1)
				(type default)
			)
			(layer "B.Fab")
		)
		(fp_line
			(start 0.12065 -0.2794)
			(end -0.12065 -0.2794)
			(stroke
				(width 0.1)
				(type default)
			)
			(layer "B.Fab")
		)
		(fp_line
			(start -0.67945 -0.3048)
			(end -0.67945 0.3048)
			(stroke
				(width 0.1)
				(type default)
			)
			(layer "B.Fab")
		)
		(fp_line
			(start -0.12065 -0.3048)
			(end -0.67945 -0.3048)
			(stroke
				(width 0.1)
				(type default)
			)
			(layer "B.Fab")
		)
		(fp_line
			(start 0.12065 -0.305054)
			(end 0.12065 -0.2794)
			(stroke
				(width 0.1)
				(type default)
			)
			(layer "B.Fab")
		)
		(fp_line
			(start 0.67945 -0.305054)
			(end 0.12065 -0.305054)
			(stroke
				(width 0.1)
				(type default)
			)
			(layer "B.Fab")
		)
		(pad "1" smd circle
			(at 0.40005 0 90)
			(size 0 0)
			(layers "B.Cu" "B.Mask" "B.Paste")
			(net "PWRGD_DRAMPWRGD_CPU0_CD_R_LVC1")
		)
		(pad "2" smd circle
			(at -0.40005 0 90)
			(size 0 0)
			(layers "B.Cu" "B.Mask" "B.Paste")
			(net "PWRGD_DRAMPWRGD_CPU0_CD_LVC1_R2")
		)
	)
	(footprint ""
		(layer "B.Cu")
		(at 382.782064 -186.935364 90)
		(property "Reference" "R292"
			(at 0 0 90)
			(layer "B.SilkS")
			(hide yes)
			(effects
				(font
					(size 1.27 1.27)
				)
				(justify mirror)
			)
		)
		(property "Value" ""
			(at 0 0 90)
			(layer "B.Fab")
			(effects
				(font
					(size 1.27 1.27)
				)
				(justify mirror)
			)
		)
		(duplicate_pad_numbers_are_jumpers no)
		(fp_line
			(start 0.7874 -0.4064)
			(end -0.7874 -0.4064)
			(stroke
				(width 0.1524)
				(type default)
			)
			(layer "B.SilkS")
		)
		(fp_line
			(start -0.7874 -0.4064)
			(end -0.7874 0.4064)
			(stroke
				(width 0.1524)
				(type default)
			)
			(layer "B.SilkS")
		)
		(fp_line
			(start 0.7874 0.4064)
			(end 0.7874 -0.4064)
			(stroke
				(width 0.1524)
				(type default)
			)
			(layer "B.SilkS")
		)
		(fp_line
			(start -0.7874 0.4064)
			(end 0.7874 0.4064)
			(stroke
				(width 0.1524)
				(type default)
			)
			(layer "B.SilkS")
		)
		(fp_line
			(start 0.67945 -0.305054)
			(end 0.12065 -0.305054)
			(stroke
				(width 0.1)
				(type default)
			)
			(layer "B.Fab")
		)
		(fp_line
			(start 0.12065 -0.305054)
			(end 0.12065 -0.2794)
			(stroke
				(width 0.1)
				(type default)
			)
			(layer "B.Fab")
		)
		(fp_line
			(start -0.12065 -0.3048)
			(end -0.67945 -0.3048)
			(stroke
				(width 0.1)
				(type default)
			)
			(layer "B.Fab")
		)
		(fp_line
			(start -0.67945 -0.3048)
			(end -0.67945 0.3048)
			(stroke
				(width 0.1)
				(type default)
			)
			(layer "B.Fab")
		)
		(fp_line
			(start 0.12065 -0.2794)
			(end -0.12065 -0.2794)
			(stroke
				(width 0.1)
				(type default)
			)
			(layer "B.Fab")
		)
		(fp_line
			(start -0.12065 -0.2794)
			(end -0.12065 -0.3048)
			(stroke
				(width 0.1)
				(type default)
			)
			(layer "B.Fab")
		)
		(fp_line
			(start 0.12065 0.2794)
			(end 0.12065 0.3048)
			(stroke
				(width 0.1)
				(type default)
			)
			(layer "B.Fab")
		)
		(fp_line
			(start -0.120396 0.2794)
			(end 0.12065 0.2794)
			(stroke
				(width 0.1)
				(type default)
			)
			(layer "B.Fab")
		)
		(fp_line
			(start 0.67945 0.3048)
			(end 0.67945 -0.305054)
			(stroke
				(width 0.1)
				(type default)
			)
			(layer "B.Fab")
		)
		(fp_line
			(start 0.12065 0.3048)
			(end 0.67945 0.3048)
			(stroke
				(width 0.1)
				(type default)
			)
			(layer "B.Fab")
		)
		(fp_line
			(start -0.120396 0.3048)
			(end -0.120396 0.2794)
			(stroke
				(width 0.1)
				(type default)
			)
			(layer "B.Fab")
		)
		(fp_line
			(start -0.67945 0.3048)
			(end -0.120396 0.3048)
			(stroke
				(width 0.1)
				(type default)
			)
			(layer "B.Fab")
		)
		(pad "1" smd circle
			(at 0.40005 0 270)
			(size 0 0)
			(layers "B.Cu" "B.Mask" "B.Paste")
			(net "PVNN_TERM_CPU0")
		)
		(pad "2" smd circle
			(at -0.40005 0 270)
			(size 0 0)
			(layers "B.Cu" "B.Mask" "B.Paste")
			(net "PD_CPU0_TXT_PLTEN")
		)
	)
	(footprint ""
		(layer "B.Cu")
		(at 185.53684 -104.491028 180)
		(property "Reference" "R171"
			(at 0 0 0)
			(layer "B.SilkS")
			(hide yes)
			(effects
				(font
					(size 1.27 1.27)
				)
				(justify mirror)
			)
		)
		(property "Value" ""
			(at 0 0 0)
			(layer "B.Fab")
			(effects
				(font
					(size 1.27 1.27)
				)
				(justify mirror)
			)
		)
		(duplicate_pad_numbers_are_jumpers no)
		(fp_line
			(start 0.7874 0.4064)
			(end 0.7874 -0.4064)
			(stroke
				(width 0.1524)
				(type default)
			)
			(layer "B.SilkS")
		)
		(fp_line
			(start 0.7874 -0.4064)
			(end -0.7874 -0.4064)
			(stroke
				(width 0.1524)
				(type default)
			)
			(layer "B.SilkS")
		)
		(fp_line
			(start -0.7874 0.4064)
			(end 0.7874 0.4064)
			(stroke
				(width 0.1524)
				(type default)
			)
			(layer "B.SilkS")
		)
		(fp_line
			(start -0.7874 -0.4064)
			(end -0.7874 0.4064)
			(stroke
				(width 0.1524)
				(type default)
			)
			(layer "B.SilkS")
		)
		(fp_line
			(start 0.67945 0.3048)
			(end 0.67945 -0.305054)
			(stroke
				(width 0.1)
				(type default)
			)
			(layer "B.Fab")
		)
		(fp_line
			(start 0.67945 -0.305054)
			(end 0.12065 -0.305054)
			(stroke
				(width 0.1)
				(type default)
			)
			(layer "B.Fab")
		)
		(fp_line
			(start 0.12065 0.3048)
			(end 0.67945 0.3048)
			(stroke
				(width 0.1)
				(type default)
			)
			(layer "B.Fab")
		)
		(fp_line
			(start 0.12065 0.2794)
			(end 0.12065 0.3048)
			(stroke
				(width 0.1)
				(type default)
			)
			(layer "B.Fab")
		)
		(fp_line
			(start 0.12065 -0.2794)
			(end -0.12065 -0.2794)
			(stroke
				(width 0.1)
				(type default)
			)
			(layer "B.Fab")
		)
		(fp_line
			(start 0.12065 -0.305054)
			(end 0.12065 -0.2794)
			(stroke
				(width 0.1)
				(type default)
			)
			(layer "B.Fab")
		)
		(fp_line
			(start -0.120396 0.3048)
			(end -0.120396 0.2794)
			(stroke
				(width 0.1)
				(type default)
			)
			(layer "B.Fab")
		)
		(fp_line
			(start -0.120396 0.2794)
			(end 0.12065 0.2794)
			(stroke
				(width 0.1)
				(type default)
			)
			(layer "B.Fab")
		)
		(fp_line
			(start -0.12065 -0.2794)
			(end -0.12065 -0.3048)
			(stroke
				(width 0.1)
				(type default)
			)
			(layer "B.Fab")
		)
		(fp_line
			(start -0.12065 -0.3048)
			(end -0.67945 -0.3048)
			(stroke
				(width 0.1)
				(type default)
			)
			(layer "B.Fab")
		)
		(fp_line
			(start -0.67945 0.3048)
			(end -0.120396 0.3048)
			(stroke
				(width 0.1)
				(type default)
			)
			(layer "B.Fab")
		)
		(fp_line
			(start -0.67945 -0.3048)
			(end -0.67945 0.3048)
			(stroke
				(width 0.1)
				(type default)
			)
			(layer "B.Fab")
		)
		(pad "1" smd circle
			(at 0.40005 0)
			(size 0 0)
			(layers "B.Cu" "B.Mask" "B.Paste")
			(net "RST_CPU0_LVC1_R_N")
		)
		(pad "2" smd circle
			(at -0.40005 0)
			(size 0 0)
			(layers "B.Cu" "B.Mask" "B.Paste")
			(net "RST_CPU0_BUF_R_N")
		)
	)
	(footprint ""
		(layer "B.Cu")
		(at 166.369746 -319.268856 180)
		(property "Reference" "C93"
			(at 0 0 0)
			(layer "B.SilkS")
			(hide yes)
			(effects
				(font
					(size 1.27 1.27)
				)
				(justify mirror)
			)
		)
		(property "Value" ""
			(at 0 0 0)
			(layer "B.Fab")
			(effects
				(font
					(size 1.27 1.27)
				)
				(justify mirror)
			)
		)
		(duplicate_pad_numbers_are_jumpers no)
		(fp_line
			(start 0.7874 0.4064)
			(end 0.7874 -0.4064)
			(stroke
				(width 0.1524)
				(type default)
			)
			(layer "B.SilkS")
		)
		(fp_line
			(start 0.7874 -0.4064)
			(end -0.7874 -0.4064)
			(stroke
				(width 0.1524)
				(type default)
			)
			(layer "B.SilkS")
		)
		(fp_line
			(start -0.7874 0.4064)
			(end 0.7874 0.4064)
			(stroke
				(width 0.1524)
				(type default)
			)
			(layer "B.SilkS")
		)
		(fp_line
			(start -0.7874 -0.4064)
			(end -0.7874 0.4064)
			(stroke
				(width 0.1524)
				(type default)
			)
			(layer "B.SilkS")
		)
		(fp_line
			(start 0.67945 0.3048)
			(end 0.67945 -0.305054)
			(stroke
				(width 0.1)
				(type default)
			)
			(layer "B.Fab")
		)
		(fp_line
			(start 0.67945 -0.305054)
			(end 0.12065 -0.305054)
			(stroke
				(width 0.1)
				(type default)
			)
			(layer "B.Fab")
		)
		(fp_line
			(start 0.12065 0.3048)
			(end 0.67945 0.3048)
			(stroke
				(width 0.1)
				(type default)
			)
			(layer "B.Fab")
		)
		(fp_line
			(start 0.12065 0.2794)
			(end 0.12065 0.3048)
			(stroke
				(width 0.1)
				(type default)
			)
			(layer "B.Fab")
		)
		(fp_line
			(start 0.12065 -0.2794)
			(end -0.12065 -0.2794)
			(stroke
				(width 0.1)
				(type default)
			)
			(layer "B.Fab")
		)
		(fp_line
			(start 0.12065 -0.305054)
			(end 0.12065 -0.2794)
			(stroke
				(width 0.1)
				(type default)
			)
			(layer "B.Fab")
		)
		(fp_line
			(start -0.120396 0.3048)
			(end -0.120396 0.2794)
			(stroke
				(width 0.1)
				(type default)
			)
			(layer "B.Fab")
		)
		(fp_line
			(start -0.120396 0.2794)
			(end 0.12065 0.2794)
			(stroke
				(width 0.1)
				(type default)
			)
			(layer "B.Fab")
		)
		(fp_line
			(start -0.12065 -0.2794)
			(end -0.12065 -0.3048)
			(stroke
				(width 0.1)
				(type default)
			)
			(layer "B.Fab")
		)
		(fp_line
			(start -0.12065 -0.3048)
			(end -0.67945 -0.3048)
			(stroke
				(width 0.1)
				(type default)
			)
			(layer "B.Fab")
		)
		(fp_line
			(start -0.67945 0.3048)
			(end -0.120396 0.3048)
			(stroke
				(width 0.1)
				(type default)
			)
			(layer "B.Fab")
		)
		(fp_line
			(start -0.67945 -0.3048)
			(end -0.67945 0.3048)
			(stroke
				(width 0.1)
				(type default)
			)
			(layer "B.Fab")
		)
		(pad "1" smd circle
			(at 0.40005 0)
			(size 0 0)
			(layers "B.Cu" "B.Mask" "B.Paste")
			(net "P3V3_AUX")
		)
		(pad "2" smd circle
			(at -0.40005 0)
			(size 0 0)
			(layers "B.Cu" "B.Mask" "B.Paste")
			(net "GND")
		)
	)
	(footprint ""
		(layer "B.Cu")
		(at 333.824326 -31.397702 90)
		(property "Reference" "R915"
			(at 0 0 90)
			(layer "B.SilkS")
			(hide yes)
			(effects
				(font
					(size 1.27 1.27)
				)
				(justify mirror)
			)
		)
		(property "Value" ""
			(at 0 0 90)
			(layer "B.Fab")
			(effects
				(font
					(size 1.27 1.27)
				)
				(justify mirror)
			)
		)
		(duplicate_pad_numbers_are_jumpers no)
		(fp_line
			(start 0.7874 -0.4064)
			(end -0.7874 -0.4064)
			(stroke
				(width 0.1524)
				(type default)
			)
			(layer "B.SilkS")
		)
		(fp_line
			(start -0.7874 -0.4064)
			(end -0.7874 0.4064)
			(stroke
				(width 0.1524)
				(type default)
			)
			(layer "B.SilkS")
		)
		(fp_line
			(start 0.7874 0.4064)
			(end 0.7874 -0.4064)
			(stroke
				(width 0.1524)
				(type default)
			)
			(layer "B.SilkS")
		)
		(fp_line
			(start -0.7874 0.4064)
			(end 0.7874 0.4064)
			(stroke
				(width 0.1524)
				(type default)
			)
			(layer "B.SilkS")
		)
		(fp_line
			(start 0.67945 -0.305054)
			(end 0.12065 -0.305054)
			(stroke
				(width 0.1)
				(type default)
			)
			(layer "B.Fab")
		)
		(fp_line
			(start 0.12065 -0.305054)
			(end 0.12065 -0.2794)
			(stroke
				(width 0.1)
				(type default)
			)
			(layer "B.Fab")
		)
		(fp_line
			(start -0.12065 -0.3048)
			(end -0.67945 -0.3048)
			(stroke
				(width 0.1)
				(type default)
			)
			(layer "B.Fab")
		)
		(fp_line
			(start -0.67945 -0.3048)
			(end -0.67945 0.3048)
			(stroke
				(width 0.1)
				(type default)
			)
			(layer "B.Fab")
		)
		(fp_line
			(start 0.12065 -0.2794)
			(end -0.12065 -0.2794)
			(stroke
				(width 0.1)
				(type default)
			)
			(layer "B.Fab")
		)
		(fp_line
			(start -0.12065 -0.2794)
			(end -0.12065 -0.3048)
			(stroke
				(width 0.1)
				(type default)
			)
			(layer "B.Fab")
		)
		(fp_line
			(start 0.12065 0.2794)
			(end 0.12065 0.3048)
			(stroke
				(width 0.1)
				(type default)
			)
			(layer "B.Fab")
		)
		(fp_line
			(start -0.120396 0.2794)
			(end 0.12065 0.2794)
			(stroke
				(width 0.1)
				(type default)
			)
			(layer "B.Fab")
		)
		(fp_line
			(start 0.67945 0.3048)
			(end 0.67945 -0.305054)
			(stroke
				(width 0.1)
				(type default)
			)
			(layer "B.Fab")
		)
		(fp_line
			(start 0.12065 0.3048)
			(end 0.67945 0.3048)
			(stroke
				(width 0.1)
				(type default)
			)
			(layer "B.Fab")
		)
		(fp_line
			(start -0.120396 0.3048)
			(end -0.120396 0.2794)
			(stroke
				(width 0.1)
				(type default)
			)
			(layer "B.Fab")
		)
		(fp_line
			(start -0.67945 0.3048)
			(end -0.120396 0.3048)
			(stroke
				(width 0.1)
				(type default)
			)
			(layer "B.Fab")
		)
		(pad "1" smd circle
			(at 0.40005 0 270)
			(size 0 0)
			(layers "B.Cu" "B.Mask" "B.Paste")
			(net "SPI_PCH_IO0")
		)
		(pad "2" smd circle
			(at -0.40005 0 270)
			(size 0 0)
			(layers "B.Cu" "B.Mask" "B.Paste")
			(net "SPI_SYS_MOSI")
		)
	)
)
